(kicad_pcb
	(version 20260206)
	(generator "pcbnew")
	(generator_version "10.0")
	(general
		(thickness 1.6)
		(legacy_teardrops no)
	)
	(paper "A4")
	(title_block
		(title "Bryce Canyon_R.DPB_16317-1_OCP.brd")
		(comment 1 "Bryce Canyon / footprints 1660-1667 of 2099")
	)
	(layers
		(0 "F.Cu" signal "TOP")
		(4 "In1.Cu" signal "L2GND")
		(6 "In2.Cu" signal "L3")
		(8 "In3.Cu" signal "L4VCC")
		(10 "In4.Cu" signal "L5VCC")
		(12 "In5.Cu" signal "L6")
		(14 "In6.Cu" signal "L7GND")
		(2 "B.Cu" signal "BOTTOM")
		(9 "F.Adhes" user "F.Adhesive")
		(11 "B.Adhes" user "B.Adhesive")
		(13 "F.Paste" user "Package Geometry/Pastemask Top")
		(15 "B.Paste" user "Package Geometry/Pastemask Bottom")
		(5 "F.SilkS" user "Ref Des/Silkscreen Top")
		(7 "B.SilkS" user "Ref Des/Silkscreen Bottom")
		(1 "F.Mask" user "Board Geometry/Soldermask Top")
		(3 "B.Mask" user "Board Geometry/Soldermask Bottom")
		(17 "Dwgs.User" user "User.Drawings")
		(19 "Cmts.User" user "User.Comments")
		(21 "Eco1.User" user "User.Eco1")
		(23 "Eco2.User" user "User.Eco2")
		(25 "Edge.Cuts" user "Board Geometry/Outline")
		(27 "Margin" user)
		(31 "F.CrtYd" user "Package Geometry/Place Bound Top")
		(29 "B.CrtYd" user "Package Geometry/Place Bound Bottom")
		(35 "F.Fab" user "Ref Des/Assembly Top")
		(33 "B.Fab" user "Ref Des/Assembly Bottom")
	)
	(footprint ""
		(layer "F.Cu")
		(at 86.868 -263.271)
		(property "Reference" "R190"
			(at 0 0 0)
			(layer "F.SilkS")
			(hide yes)
			(effects
				(font
					(size 1.27 1.27)
				)
			)
		)
		(property "Value" "2R6F-GP"
			(at -0.0508 -4.8514 0)
			(unlocked yes)
			(layer "F.Fab")
			(hide yes)
			(effects
				(font
					(size 1.016 1.016)
					(thickness 0.1524)
				)
			)
		)
		(property "Device Type" "R1206H26"
			(at 0 -6.3754 0)
			(unlocked yes)
			(layer "F.Fab")
			(hide yes)
			(effects
				(font
					(size 1.016 1.016)
					(thickness 0.1524)
				)
			)
		)
		(duplicate_pad_numbers_are_jumpers no)
		(fp_line
			(start -1.016 -2.2352)
			(end 1.016 -2.2352)
			(stroke
				(width 0.1524)
				(type default)
			)
			(layer "F.SilkS")
		)
		(fp_line
			(start -1.016 2.2352)
			(end -1.016 -2.2352)
			(stroke
				(width 0.1524)
				(type default)
			)
			(layer "F.SilkS")
		)
		(fp_line
			(start 1.016 -2.2352)
			(end 1.016 2.2352)
			(stroke
				(width 0.1524)
				(type default)
			)
			(layer "F.SilkS")
		)
		(fp_line
			(start 1.016 2.2352)
			(end -1.016 2.2352)
			(stroke
				(width 0.1524)
				(type default)
			)
			(layer "F.SilkS")
		)
		(fp_rect
			(start -1.0922 2.3114)
			(end 1.0922 -2.3114)
			(stroke
				(width 0)
				(type default)
			)
			(fill no)
			(layer "F.CrtYd")
		)
		(fp_poly
			(pts
				(xy -1.0922 -2.3114) (xy 1.0922 -2.3114) (xy 1.0922 2.3114) (xy -1.0922 2.3114)
			)
			(stroke
				(width 0)
				(type default)
			)
			(fill no)
			(layer "F.Fab")
		)
		(pad "1" smd rect
			(at 0 -1.397)
			(size 1.651 1.27)
			(layers "F.Cu" "F.Mask" "F.Paste")
			(net "P5V_HDD2")
		)
		(pad "2" smd rect
			(at 0 1.397)
			(size 1.651 1.27)
			(layers "F.Cu" "F.Mask" "F.Paste")
			(net "5V_PRE_2")
		)
	)
	(footprint ""
		(layer "F.Cu")
		(at 248.525538 -135.479282 90)
		(property "Reference" "C58"
			(at 0 0 90)
			(layer "F.SilkS")
			(hide yes)
			(effects
				(font
					(size 1.27 1.27)
				)
			)
		)
		(property "Value" "SCD1U16V2KX-3GP"
			(at 1.1811 -2.7051 90)
			(unlocked yes)
			(layer "F.Fab")
			(hide yes)
			(effects
				(font
					(size 1.016 1.016)
					(thickness 0.1524)
				)
			)
		)
		(property "Device Type" "C402H22"
			(at 1.1811 -4.2291 90)
			(unlocked yes)
			(layer "F.Fab")
			(hide yes)
			(effects
				(font
					(size 1.016 1.016)
					(thickness 0.1524)
				)
			)
		)
		(duplicate_pad_numbers_are_jumpers no)
		(fp_rect
			(start -0.4318 0.9525)
			(end 0.4318 -0.9525)
			(stroke
				(width 0)
				(type default)
			)
			(fill no)
			(layer "F.CrtYd")
		)
		(fp_rect
			(start -0.4318 0.9525)
			(end 0.4318 -0.9525)
			(stroke
				(width 0)
				(type default)
			)
			(fill no)
			(layer "F.Fab")
		)
		(pad "1" smd custom
			(at 0 -0.4445 90)
			(size 0.1524 0.1524)
			(layers "F.Cu" "F.Mask" "F.Paste")
			(net "P3V3_STBY_B")
			(options
				(clearance outline)
				(anchor circle)
			)
			(primitives
				(gr_poly
					(pts
						(arc
							(start 0.3048 -0.2032)
							(mid 0.275042 -0.275042)
							(end 0.2032 -0.3048)
						)
						(arc
							(start -0.2032 -0.3048)
							(mid -0.275042 -0.275042)
							(end -0.3048 -0.2032)
						)
						(arc
							(start -0.3048 0.2032)
							(mid -0.275042 0.275042)
							(end -0.2032 0.3048)
						)
						(arc
							(start 0.2032 0.3048)
							(mid 0.275042 0.275042)
							(end 0.3048 0.2032)
						)
					)
					(width 0)
					(fill yes)
				)
			)
		)
		(pad "2" smd custom
			(at 0 0.4445 90)
			(size 0.1524 0.1524)
			(layers "F.Cu" "F.Mask" "F.Paste")
			(net "GND")
			(options
				(clearance outline)
				(anchor circle)
			)
			(primitives
				(gr_poly
					(pts
						(arc
							(start 0.3048 -0.2032)
							(mid 0.275042 -0.275042)
							(end 0.2032 -0.3048)
						)
						(arc
							(start -0.2032 -0.3048)
							(mid -0.275042 -0.275042)
							(end -0.3048 -0.2032)
						)
						(arc
							(start -0.3048 0.2032)
							(mid -0.275042 0.275042)
							(end -0.2032 0.3048)
						)
						(arc
							(start 0.2032 0.3048)
							(mid 0.275042 0.275042)
							(end 0.3048 0.2032)
						)
					)
					(width 0)
					(fill yes)
				)
			)
		)
	)
	(footprint ""
		(layer "F.Cu")
		(at 129.921 -262.128 90)
		(property "Reference" "C75"
			(at 0 0 90)
			(layer "F.SilkS")
			(hide yes)
			(effects
				(font
					(size 1.27 1.27)
				)
			)
		)
		(property "Value" "SCD01U50V2KX-1GP"
			(at 1.1811 -2.7051 90)
			(unlocked yes)
			(layer "F.Fab")
			(hide yes)
			(effects
				(font
					(size 1.016 1.016)
					(thickness 0.1524)
				)
			)
		)
		(property "Device Type" "C402H22"
			(at 1.1811 -4.2291 90)
			(unlocked yes)
			(layer "F.Fab")
			(hide yes)
			(effects
				(font
					(size 1.016 1.016)
					(thickness 0.1524)
				)
			)
		)
		(duplicate_pad_numbers_are_jumpers no)
		(fp_rect
			(start -0.4318 0.9525)
			(end 0.4318 -0.9525)
			(stroke
				(width 0)
				(type default)
			)
			(fill no)
			(layer "F.CrtYd")
		)
		(fp_rect
			(start -0.4318 0.9525)
			(end 0.4318 -0.9525)
			(stroke
				(width 0)
				(type default)
			)
			(fill no)
			(layer "F.Fab")
		)
		(pad "1" smd custom
			(at 0 -0.4445 90)
			(size 0.1524 0.1524)
			(layers "F.Cu" "F.Mask" "F.Paste")
			(net "HDD_PRSNT_3")
			(options
				(clearance outline)
				(anchor circle)
			)
			(primitives
				(gr_poly
					(pts
						(arc
							(start 0.3048 -0.2032)
							(mid 0.275042 -0.275042)
							(end 0.2032 -0.3048)
						)
						(arc
							(start -0.2032 -0.3048)
							(mid -0.275042 -0.275042)
							(end -0.3048 -0.2032)
						)
						(arc
							(start -0.3048 0.2032)
							(mid -0.275042 0.275042)
							(end -0.2032 0.3048)
						)
						(arc
							(start 0.2032 0.3048)
							(mid 0.275042 0.275042)
							(end 0.3048 0.2032)
						)
					)
					(width 0)
					(fill yes)
				)
			)
		)
		(pad "2" smd custom
			(at 0 0.4445 90)
			(size 0.1524 0.1524)
			(layers "F.Cu" "F.Mask" "F.Paste")
			(net "GND")
			(options
				(clearance outline)
				(anchor circle)
			)
			(primitives
				(gr_poly
					(pts
						(arc
							(start 0.3048 -0.2032)
							(mid 0.275042 -0.275042)
							(end 0.2032 -0.3048)
						)
						(arc
							(start -0.2032 -0.3048)
							(mid -0.275042 -0.275042)
							(end -0.3048 -0.2032)
						)
						(arc
							(start -0.3048 0.2032)
							(mid -0.275042 0.275042)
							(end -0.2032 0.3048)
						)
						(arc
							(start 0.2032 0.3048)
							(mid 0.275042 0.275042)
							(end 0.3048 0.2032)
						)
					)
					(width 0)
					(fill yes)
				)
			)
		)
	)
	(footprint ""
		(layer "F.Cu")
		(at 23.112476 -221.58325 -90)
		(property "Reference" "R1104"
			(at 0 0 270)
			(layer "F.SilkS")
			(hide yes)
			(effects
				(font
					(size 1.27 1.27)
				)
			)
		)
		(property "Value" "3D01R5F-GP"
			(at 0 -8.9535 270)
			(unlocked yes)
			(layer "F.Fab")
			(hide yes)
			(effects
				(font
					(size 1.27 1.016)
					(thickness 0.1524)
				)
			)
		)
		(property "Device Type" "R805H24"
			(at 0 -10.6299 270)
			(unlocked yes)
			(layer "F.Fab")
			(hide yes)
			(effects
				(font
					(size 1.27 1.016)
					(thickness 0.1524)
				)
			)
		)
		(duplicate_pad_numbers_are_jumpers no)
		(fp_line
			(start -0.889 1.7018)
			(end 0.889 1.7018)
			(stroke
				(width 0.1524)
				(type default)
			)
			(layer "F.SilkS")
		)
		(fp_line
			(start 0.889 1.7018)
			(end 0.889 -0.508)
			(stroke
				(width 0.1524)
				(type default)
			)
			(layer "F.SilkS")
		)
		(fp_line
			(start -0.889 0.0762)
			(end -0.889 1.7018)
			(stroke
				(width 0.1524)
				(type default)
			)
			(layer "F.SilkS")
		)
		(fp_line
			(start -0.889 -1.7018)
			(end -0.889 0.2794)
			(stroke
				(width 0.1524)
				(type default)
			)
			(layer "F.SilkS")
		)
		(fp_line
			(start 0.889 -1.7018)
			(end 0.889 -0.381)
			(stroke
				(width 0.1524)
				(type default)
			)
			(layer "F.SilkS")
		)
		(fp_line
			(start 0.889 -1.7018)
			(end -0.889 -1.7018)
			(stroke
				(width 0.1524)
				(type default)
			)
			(layer "F.SilkS")
		)
		(fp_poly
			(pts
				(xy 0.9652 -1.778) (xy 0.9652 1.778) (xy -0.9652 1.778) (xy -0.9652 -1.778)
			)
			(stroke
				(width 0)
				(type default)
			)
			(fill no)
			(layer "F.CrtYd")
		)
		(fp_rect
			(start -0.9652 1.778)
			(end 0.9652 -1.778)
			(stroke
				(width 0)
				(type default)
			)
			(fill no)
			(layer "F.Fab")
		)
		(pad "1" smd rect
			(at 0 -0.9652 270)
			(size 1.397 1.143)
			(layers "F.Cu" "F.Mask" "F.Paste")
			(net "P5V_B_1_SNB")
		)
		(pad "2" smd rect
			(at 0 0.9652 270)
			(size 1.397 1.143)
			(layers "F.Cu" "F.Mask" "F.Paste")
			(net "GND")
		)
	)
	(footprint ""
		(layer "F.Cu")
		(at 66.802 -147.066 90)
		(property "Reference" "C205"
			(at 0 0 90)
			(layer "F.SilkS")
			(hide yes)
			(effects
				(font
					(size 1.27 1.27)
				)
			)
		)
		(property "Value" "SCD01U50V2KX-1GP"
			(at 1.1811 -2.7051 90)
			(unlocked yes)
			(layer "F.Fab")
			(hide yes)
			(effects
				(font
					(size 1.016 1.016)
					(thickness 0.1524)
				)
			)
		)
		(property "Device Type" "C402H22"
			(at 1.1811 -4.2291 90)
			(unlocked yes)
			(layer "F.Fab")
			(hide yes)
			(effects
				(font
					(size 1.016 1.016)
					(thickness 0.1524)
				)
			)
		)
		(duplicate_pad_numbers_are_jumpers no)
		(fp_rect
			(start -0.4318 0.9525)
			(end 0.4318 -0.9525)
			(stroke
				(width 0)
				(type default)
			)
			(fill no)
			(layer "F.CrtYd")
		)
		(fp_rect
			(start -0.4318 0.9525)
			(end 0.4318 -0.9525)
			(stroke
				(width 0)
				(type default)
			)
			(fill no)
			(layer "F.Fab")
		)
		(pad "1" smd custom
			(at 0 -0.4445 90)
			(size 0.1524 0.1524)
			(layers "F.Cu" "F.Mask" "F.Paste")
			(net "HDD_PRSNT_13")
			(options
				(clearance outline)
				(anchor circle)
			)
			(primitives
				(gr_poly
					(pts
						(arc
							(start 0.3048 -0.2032)
							(mid 0.275042 -0.275042)
							(end 0.2032 -0.3048)
						)
						(arc
							(start -0.2032 -0.3048)
							(mid -0.275042 -0.275042)
							(end -0.3048 -0.2032)
						)
						(arc
							(start -0.3048 0.2032)
							(mid -0.275042 0.275042)
							(end -0.2032 0.3048)
						)
						(arc
							(start 0.2032 0.3048)
							(mid 0.275042 0.275042)
							(end 0.3048 0.2032)
						)
					)
					(width 0)
					(fill yes)
				)
			)
		)
		(pad "2" smd custom
			(at 0 0.4445 90)
			(size 0.1524 0.1524)
			(layers "F.Cu" "F.Mask" "F.Paste")
			(net "GND")
			(options
				(clearance outline)
				(anchor circle)
			)
			(primitives
				(gr_poly
					(pts
						(arc
							(start 0.3048 -0.2032)
							(mid 0.275042 -0.275042)
							(end 0.2032 -0.3048)
						)
						(arc
							(start -0.2032 -0.3048)
							(mid -0.275042 -0.275042)
							(end -0.3048 -0.2032)
						)
						(arc
							(start -0.3048 0.2032)
							(mid -0.275042 0.275042)
							(end -0.2032 0.3048)
						)
						(arc
							(start 0.2032 0.3048)
							(mid 0.275042 0.275042)
							(end 0.3048 0.2032)
						)
					)
					(width 0)
					(fill yes)
				)
			)
		)
	)
	(footprint ""
		(layer "F.Cu")
		(at 416.3822 -31.6484)
		(property "Reference" "C461"
			(at 0 0 0)
			(layer "F.SilkS")
			(hide yes)
			(effects
				(font
					(size 1.27 1.27)
				)
			)
		)
		(property "Value" "SCD01U50V2KX-1GP"
			(at 1.1811 -2.7051 0)
			(unlocked yes)
			(layer "F.Fab")
			(hide yes)
			(effects
				(font
					(size 1.016 1.016)
					(thickness 0.1524)
				)
			)
		)
		(property "Device Type" "C402H22"
			(at 1.1811 -4.2291 0)
			(unlocked yes)
			(layer "F.Fab")
			(hide yes)
			(effects
				(font
					(size 1.016 1.016)
					(thickness 0.1524)
				)
			)
		)
		(duplicate_pad_numbers_are_jumpers no)
		(fp_rect
			(start -0.4318 0.9525)
			(end 0.4318 -0.9525)
			(stroke
				(width 0)
				(type default)
			)
			(fill no)
			(layer "F.CrtYd")
		)
		(fp_rect
			(start -0.4318 0.9525)
			(end 0.4318 -0.9525)
			(stroke
				(width 0)
				(type default)
			)
			(fill no)
			(layer "F.Fab")
		)
		(pad "1" smd custom
			(at 0 -0.4445)
			(size 0.1524 0.1524)
			(layers "F.Cu" "F.Mask" "F.Paste")
			(net "HDD_PRSNT_33")
			(options
				(clearance outline)
				(anchor circle)
			)
			(primitives
				(gr_poly
					(pts
						(arc
							(start 0.3048 -0.2032)
							(mid 0.275042 -0.275042)
							(end 0.2032 -0.3048)
						)
						(arc
							(start -0.2032 -0.3048)
							(mid -0.275042 -0.275042)
							(end -0.3048 -0.2032)
						)
						(arc
							(start -0.3048 0.2032)
							(mid -0.275042 0.275042)
							(end -0.2032 0.3048)
						)
						(arc
							(start 0.2032 0.3048)
							(mid 0.275042 0.275042)
							(end 0.3048 0.2032)
						)
					)
					(width 0)
					(fill yes)
				)
			)
		)
		(pad "2" smd custom
			(at 0 0.4445)
			(size 0.1524 0.1524)
			(layers "F.Cu" "F.Mask" "F.Paste")
			(net "GND")
			(options
				(clearance outline)
				(anchor circle)
			)
			(primitives
				(gr_poly
					(pts
						(arc
							(start 0.3048 -0.2032)
							(mid 0.275042 -0.275042)
							(end 0.2032 -0.3048)
						)
						(arc
							(start -0.2032 -0.3048)
							(mid -0.275042 -0.275042)
							(end -0.3048 -0.2032)
						)
						(arc
							(start -0.3048 0.2032)
							(mid -0.275042 0.275042)
							(end -0.2032 0.3048)
						)
						(arc
							(start 0.2032 0.3048)
							(mid 0.275042 0.275042)
							(end 0.3048 0.2032)
						)
					)
					(width 0)
					(fill yes)
				)
			)
		)
	)
	(footprint ""
		(layer "F.Cu")
		(at 259.490972 -372.32971)
		(property "Reference" "R1031"
			(at 0 0 0)
			(layer "F.SilkS")
			(hide yes)
			(effects
				(font
					(size 1.27 1.27)
				)
			)
		)
		(property "Value" "10KR2J-3-GP"
			(at 0.064008 -3.993896 0)
			(unlocked yes)
			(layer "F.Fab")
			(hide yes)
			(effects
				(font
					(size 1.016 1.016)
					(thickness 0.1524)
				)
			)
		)
		(property "Device Type" "R402H16"
			(at 0.064008 -5.517896 0)
			(unlocked yes)
			(layer "F.Fab")
			(hide yes)
			(effects
				(font
					(size 1.016 1.016)
					(thickness 0.1524)
				)
			)
		)
		(duplicate_pad_numbers_are_jumpers no)
		(fp_line
			(start -0.508 -0.9398)
			(end -0.508 0.9398)
			(stroke
				(width 0.1524)
				(type default)
			)
			(layer "F.SilkS")
		)
		(fp_line
			(start 0.508 -0.9398)
			(end -0.508 -0.9398)
			(stroke
				(width 0.1524)
				(type default)
			)
			(layer "F.SilkS")
		)
		(fp_rect
			(start -0.508 0.9398)
			(end 0.508 -0.9398)
			(stroke
				(width 0)
				(type default)
			)
			(fill no)
			(layer "F.CrtYd")
		)
		(fp_rect
			(start -0.508 0.9398)
			(end 0.508 -0.9398)
			(stroke
				(width 0)
				(type default)
			)
			(fill no)
			(layer "F.Fab")
		)
		(pad "1" smd custom
			(at 0 -0.4445)
			(size 0.1397 0.1397)
			(layers "F.Cu" "F.Mask" "F.Paste")
			(net "GND")
			(options
				(clearance outline)
				(anchor circle)
			)
			(primitives
				(gr_poly
					(pts
						(arc
							(start -0.1778 -0.2794)
							(mid -0.249642 -0.249642)
							(end -0.2794 -0.1778)
						)
						(arc
							(start -0.2794 0.1778)
							(mid -0.249642 0.249642)
							(end -0.1778 0.2794)
						)
						(arc
							(start 0.1778 0.2794)
							(mid 0.249642 0.249642)
							(end 0.2794 0.1778)
						)
						(arc
							(start 0.2794 -0.1778)
							(mid 0.249642 -0.249642)
							(end 0.1778 -0.2794)
						)
					)
					(width 0)
					(fill yes)
				)
			)
		)
		(pad "2" smd custom
			(at 0 0.4445)
			(size 0.1397 0.1397)
			(layers "F.Cu" "F.Mask" "F.Paste")
			(net "MB3_RETRY_R")
			(options
				(clearance outline)
				(anchor circle)
			)
			(primitives
				(gr_poly
					(pts
						(arc
							(start -0.1778 -0.2794)
							(mid -0.249642 -0.249642)
							(end -0.2794 -0.1778)
						)
						(arc
							(start -0.2794 0.1778)
							(mid -0.249642 0.249642)
							(end -0.1778 0.2794)
						)
						(arc
							(start 0.1778 0.2794)
							(mid 0.249642 0.249642)
							(end 0.2794 0.1778)
						)
						(arc
							(start 0.2794 -0.1778)
							(mid 0.249642 -0.249642)
							(end 0.1778 -0.2794)
						)
					)
					(width 0)
					(fill yes)
				)
			)
		)
	)
	(footprint ""
		(layer "F.Cu")
		(at 441.96 -214.249)
		(property "Reference" "R367"
			(at 0 0 0)
			(layer "F.SilkS")
			(hide yes)
			(effects
				(font
					(size 1.27 1.27)
				)
			)
		)
		(property "Value" "91R3F-1-GP"
			(at -0.0254 -2.5146 0)
			(unlocked yes)
			(layer "F.Fab")
			(hide yes)
			(effects
				(font
					(size 1.016 1.016)
					(thickness 0.1524)
				)
			)
		)
		(property "Device Type" "R603H22"
			(at -0.0254 -4.0386 0)
			(unlocked yes)
			(layer "F.Fab")
			(hide yes)
			(effects
				(font
					(size 1.016 1.016)
					(thickness 0.1524)
				)
			)
		)
		(duplicate_pad_numbers_are_jumpers no)
		(fp_line
			(start -0.4826 0)
			(end -0.2032 0)
			(stroke
				(width 0.2032)
				(type default)
			)
			(layer "F.SilkS")
		)
		(fp_line
			(start 0.2032 0)
			(end 0.4826 0)
			(stroke
				(width 0.2032)
				(type default)
			)
			(layer "F.SilkS")
		)
		(fp_rect
			(start -0.5842 1.3335)
			(end 0.5842 -1.3335)
			(stroke
				(width 0)
				(type default)
			)
			(fill no)
			(layer "F.CrtYd")
		)
		(fp_rect
			(start -0.5842 1.3335)
			(end 0.5842 -1.3335)
			(stroke
				(width 0)
				(type default)
			)
			(fill no)
			(layer "F.Fab")
		)
		(pad "1" smd custom
			(at 0 -0.762)
			(size 0.2159 0.2159)
			(layers "F.Cu" "F.Mask" "F.Paste")
			(net "P5V_B_3")
			(options
				(clearance outline)
				(anchor circle)
			)
			(primitives
				(gr_poly
					(pts
						(arc
							(start -0.3302 -0.4318)
							(mid -0.402042 -0.402042)
							(end -0.4318 -0.3302)
						)
						(arc
							(start -0.4318 0.3302)
							(mid -0.402042 0.402042)
							(end -0.3302 0.4318)
						)
						(arc
							(start 0.3302 0.4318)
							(mid 0.402042 0.402042)
							(end 0.4318 0.3302)
						)
						(arc
							(start 0.4318 -0.3302)
							(mid 0.402042 -0.402042)
							(end 0.3302 -0.4318)
						)
					)
					(width 0)
					(fill yes)
				)
			)
		)
		(pad "2" smd custom
			(at 0 0.762)
			(size 0.2159 0.2159)
			(layers "F.Cu" "F.Mask" "F.Paste")
			(net "DRV_ACT_10")
			(options
				(clearance outline)
				(anchor circle)
			)
			(primitives
				(gr_poly
					(pts
						(arc
							(start -0.3302 -0.4318)
							(mid -0.402042 -0.402042)
							(end -0.4318 -0.3302)
						)
						(arc
							(start -0.4318 0.3302)
							(mid -0.402042 0.402042)
							(end -0.3302 0.4318)
						)
						(arc
							(start 0.3302 0.4318)
							(mid 0.402042 0.402042)
							(end 0.4318 0.3302)
						)
						(arc
							(start 0.4318 -0.3302)
							(mid 0.402042 -0.402042)
							(end 0.3302 -0.4318)
						)
					)
					(width 0)
					(fill yes)
				)
			)
		)
	)
)
